# Stackup_F0T_PDB_GPU_10L_2p36mm_IT-170GT_RTF_Rev0p2_20211201.xls — Stackup (pcb-stackup)
| STACKUP |  |  |  | Target Z (ohms) - MicroStrip |  |  |  |  | 50 | Breakout |
|  |  |  |  | Target Z (ohms) - StripLine |  |  |  |  | 50 |  |
|  |  |  |  | Z tolerance |  |  |  |  | 0.1 |  |
|  |  |  |  | Z Type |  |  |  |  | Single | Single |
| Layer# | Material | Description |  | Copper Weight (oz) | Thickness (mil) | Tolerance (mil) | Glass Fabric | Er | Width | Width |
|  |  |  | Soldermask |  | 0.6 |  |  | 3.8 |  |  |
| 1 |  |  | TOP | 0.5+plating | 1.95 |  |  |  | 6.8 | 4 |
|  | IT-170GT |  | PP |  | 4 | ±0.709 | 106x2 | 3.87 |  |  |
| 2 |  |  | GND | 2 (RTF) | 2.6 |  |  |  |  |  |
|  | IT-170GT |  | CORE |  | 6 | ±0.984 | 1080x2 | 3.89 |  |  |
| 3 |  |  | IN1 | 1 (RTF) | 1.3 |  |  |  | 5.1 | 4 |
|  | IT-170GT |  | PP |  | 6 | ±0.984 | 3313x1+1078x1 | 3.89 |  |  |
| 4 |  |  | GND1 | 2 (RTF) | 2.6 |  |  |  |  |  |
|  | IT-170GT |  | CORE |  | 6 | ±0.984 | 1080x2 | 3.89 |  |  |
| 5 |  |  | VCC | 2 (RTF) | 2.6 |  |  |  |  |  |
|  | IT-170GT |  | PP |  | 25.6 | ±2.52 | Vendor Define | 4.08 |  |  |
| 6 |  |  | VCC1 | 2 (RTF) | 2.6 |  |  |  |  |  |
|  | IT-170GT |  | CORE |  | 6 | ±0.984 | 1080x2 | 3.89 |  |  |
| 7 |  |  | GND2 | 2 (RTF) | 2.6 |  |  |  |  |  |
|  | IT-170GT |  | PP |  | 6 | ±0.984 | 3313x1+1078x1 | 3.89 |  |  |
| 8 |  |  | IN2 | 1 (RTF) | 1.3 |  |  |  | 5.1 | 4 |
|  | IT-170GT |  | CORE |  | 6 | ±0.984 | 1080x2 | 3.89 |  |  |
| 9 |  |  | GND3 | 2 (RTF) | 2.6 |  |  |  |  |  |
|  | IT-170GT |  | PP |  | 4 | ±0.709 | 106x2 | 3.87 |  |  |
| 10 |  |  | BOTTOM | 0.5+plating | 1.95 |  |  |  | 6.8 | 4 |
|  |  |  | Soldermask |  | 0.6 |  |  | 3.8 |  |  |
|  |  |  |  | Total | 92.89999999999998 | ±10% |  |  |  |  |
